# SCM (Grand Teton) — schematic netlist excerpt (pin names and nets, part order shuffled) for the footprints in the layout excerpt that follows; sources: Cadence DE-HDL packaged netlist, KiCad conversion of 12092022_DA0F0TMDCD0_F0T_Management_Board_D_brd_V3_OCP.brd

PL31  Q_INDUCTOR  1UH IND  pkg SMLF  page 55 : \1\ = SW_P1V2_AUX_SW ; \2\ = P1V2_AUX
R481  Q_RES  33.2 1% CHIP  pkg 0402LF  page 45 : A = SPI_PCH_MUXED_CLK ; B = SPI_PCH_CLK_FLASH_R1
R198  Q_RES  110 1% CHIP  pkg 0402LF  page 14 : A = I3C3_SCL_R ; B = I3C3_SPD_SCL

(kicad_pcb
	(version 20260206)
	(generator "pcbnew")
	(generator_version "10.0")
	(general
		(thickness 1.6)
		(legacy_teardrops no)
	)
	(paper "A4")
	(title_block
		(title "12092022_DA0F0TMDCD0_F0T_Management_Board_D_brd_V3_OCP.brd")
		(comment 1 "Grand Teton / footprints 444-446 of 1440")
	)
	(layers
		(0 "F.Cu" signal "TOP")
		(4 "In1.Cu" signal "GND")
		(6 "In2.Cu" signal "IN1")
		(8 "In3.Cu" signal "GND1")
		(10 "In4.Cu" signal "IN2")
		(12 "In5.Cu" signal "VCC")
		(14 "In6.Cu" signal "VCC1")
		(16 "In7.Cu" signal "IN3")
		(18 "In8.Cu" signal "GND2")
		(20 "In9.Cu" signal "IN4")
		(22 "In10.Cu" signal "GND3")
		(2 "B.Cu" signal "BOTTOM")
		(9 "F.Adhes" user "F.Adhesive")
		(11 "B.Adhes" user "B.Adhesive")
		(13 "F.Paste" user "Package Geometry/Pastemask Top")
		(15 "B.Paste" user "Package Geometry/Pastemask Bottom")
		(5 "F.SilkS" user "Ref Des/Silkscreen Top")
		(7 "B.SilkS" user "Ref Des/Silkscreen Bottom")
		(1 "F.Mask" user "Board Geometry/Soldermask Top")
		(3 "B.Mask" user "Board Geometry/Soldermask Bottom")
		(17 "Dwgs.User" user "User.Drawings")
		(19 "Cmts.User" user "User.Comments")
		(21 "Eco1.User" user "User.Eco1")
		(23 "Eco2.User" user "User.Eco2")
		(25 "Edge.Cuts" user "Board Geometry/Outline")
		(27 "Margin" user)
		(31 "F.CrtYd" user "Package Geometry/Place Bound Top")
		(29 "B.CrtYd" user "Package Geometry/Place Bound Bottom")
		(35 "F.Fab" user "Ref Des/Assembly Top")
		(33 "B.Fab" user "Ref Des/Assembly Bottom")
	)
	(footprint ""
		(layer "F.Cu")
		(at 40.821102 -65.793366 90)
		(property "Reference" "R198"
			(at 0 0 90)
			(layer "F.SilkS")
			(hide yes)
			(effects
				(font
					(size 1.27 1.27)
				)
			)
		)
		(property "Value" ""
			(at 0 0 90)
			(layer "F.Fab")
			(effects
				(font
					(size 1.27 1.27)
				)
			)
		)
		(duplicate_pad_numbers_are_jumpers no)
		(fp_line
			(start 0.7874 -0.4064)
			(end 0.7874 0.4064)
			(stroke
				(width 0.1524)
				(type default)
			)
			(layer "F.SilkS")
		)
		(fp_line
			(start -0.7874 -0.4064)
			(end 0.7874 -0.4064)
			(stroke
				(width 0.1524)
				(type default)
			)
			(layer "F.SilkS")
		)
		(fp_line
			(start 0.7874 0.4064)
			(end -0.7874 0.4064)
			(stroke
				(width 0.1524)
				(type default)
			)
			(layer "F.SilkS")
		)
		(fp_line
			(start -0.7874 0.4064)
			(end -0.7874 -0.4064)
			(stroke
				(width 0.1524)
				(type default)
			)
			(layer "F.SilkS")
		)
		(fp_line
			(start -0.12065 -0.305054)
			(end -0.12065 -0.2794)
			(stroke
				(width 0.1)
				(type default)
			)
			(layer "F.Fab")
		)
		(fp_line
			(start -0.67945 -0.305054)
			(end -0.12065 -0.305054)
			(stroke
				(width 0.1)
				(type default)
			)
			(layer "F.Fab")
		)
		(fp_line
			(start 0.67945 -0.3048)
			(end 0.67945 0.3048)
			(stroke
				(width 0.1)
				(type default)
			)
			(layer "F.Fab")
		)
		(fp_line
			(start 0.12065 -0.3048)
			(end 0.67945 -0.3048)
			(stroke
				(width 0.1)
				(type default)
			)
			(layer "F.Fab")
		)
		(fp_line
			(start 0.12065 -0.2794)
			(end 0.12065 -0.3048)
			(stroke
				(width 0.1)
				(type default)
			)
			(layer "F.Fab")
		)
		(fp_line
			(start -0.12065 -0.2794)
			(end 0.12065 -0.2794)
			(stroke
				(width 0.1)
				(type default)
			)
			(layer "F.Fab")
		)
		(fp_line
			(start 0.120396 0.2794)
			(end -0.12065 0.2794)
			(stroke
				(width 0.1)
				(type default)
			)
			(layer "F.Fab")
		)
		(fp_line
			(start -0.12065 0.2794)
			(end -0.12065 0.3048)
			(stroke
				(width 0.1)
				(type default)
			)
			(layer "F.Fab")
		)
		(fp_line
			(start 0.67945 0.3048)
			(end 0.120396 0.3048)
			(stroke
				(width 0.1)
				(type default)
			)
			(layer "F.Fab")
		)
		(fp_line
			(start 0.120396 0.3048)
			(end 0.120396 0.2794)
			(stroke
				(width 0.1)
				(type default)
			)
			(layer "F.Fab")
		)
		(fp_line
			(start -0.12065 0.3048)
			(end -0.67945 0.3048)
			(stroke
				(width 0.1)
				(type default)
			)
			(layer "F.Fab")
		)
		(fp_line
			(start -0.67945 0.3048)
			(end -0.67945 -0.305054)
			(stroke
				(width 0.1)
				(type default)
			)
			(layer "F.Fab")
		)
		(pad "1" smd circle
			(at -0.40005 0 90)
			(size 0 0)
			(layers "F.Cu" "F.Mask" "F.Paste")
			(net "I3C3_SCL_R")
		)
		(pad "2" smd circle
			(at 0.40005 0 90)
			(size 0 0)
			(layers "F.Cu" "F.Mask" "F.Paste")
			(net "I3C3_SPD_SCL")
		)
	)
	(footprint ""
		(layer "F.Cu")
		(at 36.322 -106.934 -90)
		(property "Reference" "R481"
			(at 0 0 270)
			(layer "F.SilkS")
			(hide yes)
			(effects
				(font
					(size 1.27 1.27)
				)
			)
		)
		(property "Value" ""
			(at 0 0 270)
			(layer "F.Fab")
			(effects
				(font
					(size 1.27 1.27)
				)
			)
		)
		(duplicate_pad_numbers_are_jumpers no)
		(fp_line
			(start -0.7874 0.4064)
			(end -0.7874 -0.4064)
			(stroke
				(width 0.1524)
				(type default)
			)
			(layer "F.SilkS")
		)
		(fp_line
			(start 0.7874 0.4064)
			(end -0.7874 0.4064)
			(stroke
				(width 0.1524)
				(type default)
			)
			(layer "F.SilkS")
		)
		(fp_line
			(start -0.7874 -0.4064)
			(end 0.7874 -0.4064)
			(stroke
				(width 0.1524)
				(type default)
			)
			(layer "F.SilkS")
		)
		(fp_line
			(start 0.7874 -0.4064)
			(end 0.7874 0.4064)
			(stroke
				(width 0.1524)
				(type default)
			)
			(layer "F.SilkS")
		)
		(fp_line
			(start -0.67945 0.3048)
			(end -0.67945 -0.305054)
			(stroke
				(width 0.1)
				(type default)
			)
			(layer "F.Fab")
		)
		(fp_line
			(start -0.12065 0.3048)
			(end -0.67945 0.3048)
			(stroke
				(width 0.1)
				(type default)
			)
			(layer "F.Fab")
		)
		(fp_line
			(start 0.120396 0.3048)
			(end 0.120396 0.2794)
			(stroke
				(width 0.1)
				(type default)
			)
			(layer "F.Fab")
		)
		(fp_line
			(start 0.67945 0.3048)
			(end 0.120396 0.3048)
			(stroke
				(width 0.1)
				(type default)
			)
			(layer "F.Fab")
		)
		(fp_line
			(start -0.12065 0.2794)
			(end -0.12065 0.3048)
			(stroke
				(width 0.1)
				(type default)
			)
			(layer "F.Fab")
		)
		(fp_line
			(start 0.120396 0.2794)
			(end -0.12065 0.2794)
			(stroke
				(width 0.1)
				(type default)
			)
			(layer "F.Fab")
		)
		(fp_line
			(start -0.12065 -0.2794)
			(end 0.12065 -0.2794)
			(stroke
				(width 0.1)
				(type default)
			)
			(layer "F.Fab")
		)
		(fp_line
			(start 0.12065 -0.2794)
			(end 0.12065 -0.3048)
			(stroke
				(width 0.1)
				(type default)
			)
			(layer "F.Fab")
		)
		(fp_line
			(start 0.12065 -0.3048)
			(end 0.67945 -0.3048)
			(stroke
				(width 0.1)
				(type default)
			)
			(layer "F.Fab")
		)
		(fp_line
			(start 0.67945 -0.3048)
			(end 0.67945 0.3048)
			(stroke
				(width 0.1)
				(type default)
			)
			(layer "F.Fab")
		)
		(fp_line
			(start -0.67945 -0.305054)
			(end -0.12065 -0.305054)
			(stroke
				(width 0.1)
				(type default)
			)
			(layer "F.Fab")
		)
		(fp_line
			(start -0.12065 -0.305054)
			(end -0.12065 -0.2794)
			(stroke
				(width 0.1)
				(type default)
			)
			(layer "F.Fab")
		)
		(pad "1" smd circle
			(at -0.40005 0 270)
			(size 0 0)
			(layers "F.Cu" "F.Mask" "F.Paste")
			(net "SPI_PCH_MUXED_CLK")
		)
		(pad "2" smd circle
			(at 0.40005 0 270)
			(size 0 0)
			(layers "F.Cu" "F.Mask" "F.Paste")
			(net "SPI_PCH_CLK_FLASH_R1")
		)
	)
	(footprint ""
		(layer "F.Cu")
		(at 82.44967 -65.20815 -90)
		(property "Reference" "PL31"
			(at 0 0 270)
			(layer "F.SilkS")
			(hide yes)
			(effects
				(font
					(size 1.27 1.27)
				)
			)
		)
		(property "Value" ""
			(at 0 0 270)
			(layer "F.Fab")
			(effects
				(font
					(size 1.27 1.27)
				)
			)
		)
		(duplicate_pad_numbers_are_jumpers no)
		(fp_line
			(start -3.64998 3.350006)
			(end -3.64998 1.8288)
			(stroke
				(width 0.1524)
				(type default)
			)
			(layer "F.SilkS")
		)
		(fp_line
			(start 3.64998 3.350006)
			(end -3.64998 3.350006)
			(stroke
				(width 0.1524)
				(type default)
			)
			(layer "F.SilkS")
		)
		(fp_line
			(start 3.64998 1.8034)
			(end 3.64998 3.350006)
			(stroke
				(width 0.1524)
				(type default)
			)
			(layer "F.SilkS")
		)
		(fp_line
			(start -3.64998 -1.8034)
			(end -3.64998 -3.350006)
			(stroke
				(width 0.1524)
				(type default)
			)
			(layer "F.SilkS")
		)
		(fp_line
			(start -3.6576 -3.350006)
			(end 3.64998 -3.350006)
			(stroke
				(width 0.1524)
				(type default)
			)
			(layer "F.SilkS")
		)
		(fp_line
			(start 3.64998 -3.350006)
			(end 3.64998 -1.8034)
			(stroke
				(width 0.1524)
				(type default)
			)
			(layer "F.SilkS")
		)
		(fp_line
			(start -3.64998 3.350006)
			(end -3.64998 -3.350006)
			(stroke
				(width 0.1)
				(type default)
			)
			(layer "F.Fab")
		)
		(fp_line
			(start 3.64998 3.350006)
			(end -3.64998 3.350006)
			(stroke
				(width 0.1)
				(type default)
			)
			(layer "F.Fab")
		)
		(fp_line
			(start -3.64998 -3.350006)
			(end 3.64998 -3.350006)
			(stroke
				(width 0.1)
				(type default)
			)
			(layer "F.Fab")
		)
		(fp_line
			(start 3.64998 -3.350006)
			(end 3.64998 3.350006)
			(stroke
				(width 0.1)
				(type default)
			)
			(layer "F.Fab")
		)
		(pad "1" smd rect
			(at -2.92481 0 270)
			(size 2.15392 3.302)
			(layers "F.Cu" "F.Mask" "F.Paste")
			(net "SW_P1V2_AUX_SW")
		)
		(pad "2" smd rect
			(at 2.92481 0 270)
			(size 2.15392 3.302)
			(layers "F.Cu" "F.Mask" "F.Paste")
			(net "P1V2_AUX")
		)
	)
)
